# S9S_MB_2U (Grand Teton) — schematic netlist excerpt (pin names and nets, part order shuffled) for the footprints in the layout excerpt that follows; sources: Cadence DE-HDL packaged netlist, KiCad conversion of 03242023_DA0F0TMBIJ0_F0T_Motherboard_J_brd_V01_OCP.brd

H113  GND_HOLE  EMPTY  pkg TH  page 311
  GND2  = GND
  GND3  = GND
  GND4  = GND
  GND5  = GND
  GND6  = GND
  GND7  = GND
  GND8  = GND
  GND9  = GND

(kicad_pcb
	(version 20260206)
	(generator "pcbnew")
	(generator_version "10.0")
	(general
		(thickness 1.6)
		(legacy_teardrops no)
	)
	(paper "A4")
	(title_block
		(title "03242023_DA0F0TMBIJ0_F0T_Motherboard_J_brd_V01_OCP.brd")
		(comment 1 "Grand Teton / footprints 3513-3513 of 6105")
	)
	(layers
		(0 "F.Cu" signal "TOP")
		(4 "In1.Cu" signal "GND")
		(6 "In2.Cu" signal "IN1")
		(8 "In3.Cu" signal "GND1")
		(10 "In4.Cu" signal "IN2")
		(12 "In5.Cu" signal "GND2")
		(14 "In6.Cu" signal "IN3")
		(16 "In7.Cu" signal "GND3")
		(18 "In8.Cu" signal "VCC")
		(20 "In9.Cu" signal "VCC1")
		(22 "In10.Cu" signal "GND4")
		(24 "In11.Cu" signal "IN4")
		(26 "In12.Cu" signal "GND5")
		(28 "In13.Cu" signal "IN5")
		(30 "In14.Cu" signal "GND6")
		(32 "In15.Cu" signal "IN6")
		(34 "In16.Cu" signal "GND7")
		(2 "B.Cu" signal "BOTTOM")
		(9 "F.Adhes" user "F.Adhesive")
		(11 "B.Adhes" user "B.Adhesive")
		(13 "F.Paste" user "Package Geometry/Pastemask Top")
		(15 "B.Paste" user "Package Geometry/Pastemask Bottom")
		(5 "F.SilkS" user "Ref Des/Silkscreen Top")
		(7 "B.SilkS" user "Ref Des/Silkscreen Bottom")
		(1 "F.Mask" user "Board Geometry/Soldermask Top")
		(3 "B.Mask" user "Board Geometry/Soldermask Bottom")
		(17 "Dwgs.User" user "User.Drawings")
		(19 "Cmts.User" user "User.Comments")
		(21 "Eco1.User" user "User.Eco1")
		(23 "Eco2.User" user "User.Eco2")
		(25 "Edge.Cuts" user "Board Geometry/Outline")
		(27 "Margin" user)
		(31 "F.CrtYd" user "Package Geometry/Place Bound Top")
		(29 "B.CrtYd" user "Package Geometry/Place Bound Bottom")
		(35 "F.Fab" user "Ref Des/Assembly Top")
		(33 "B.Fab" user "Ref Des/Assembly Bottom")
	)
	(footprint ""
		(layer "F.Cu")
		(at 258.12496 -360.76382)
		(property "Reference" "H113"
			(at -6.92404 -7.717028 0)
			(unlocked yes)
			(layer "F.SilkS")
			(effects
				(font
					(size 0.7874 0.5842)
					(thickness 0.1524)
				)
				(justify left)
			)
		)
		(property "Value" ""
			(at 0 0 0)
			(layer "F.Fab")
			(effects
				(font
					(size 1.27 1.27)
				)
			)
		)
		(duplicate_pad_numbers_are_jumpers no)
		(fp_circle
			(center 0 0)
			(end 7.999984 0)
			(stroke
				(width 0.1524)
				(type default)
			)
			(fill no)
			(layer "F.SilkS")
		)
		(fp_circle
			(center 0 0)
			(end 7.999984 0)
			(stroke
				(width 0.1524)
				(type default)
			)
			(fill no)
			(layer "B.SilkS")
		)
		(fp_circle
			(center 0 0)
			(end 7.999984 0)
			(stroke
				(width 0.1)
				(type default)
			)
			(fill no)
			(layer "B.Fab")
		)
		(fp_circle
			(center 0 0)
			(end 7.999984 0)
			(stroke
				(width 0.1)
				(type default)
			)
			(fill no)
			(layer "F.Fab")
		)
		(pad "" np_thru_hole circle
			(at 0 0)
			(size 4.0132 4.0132)
			(drill 4.0132)
			(layers "*.Cu" "*.Mask")
			(clearance 0.381)
			(thermal_gap 0.381)
		)
		(pad "2" thru_hole circle
			(at 3.2639 0)
			(size 0.9144 0.9144)
			(drill 0.5588)
			(layers "*.Cu" "*.Mask")
			(remove_unused_layers no)
			(net "GND")
			(clearance 0.0762)
			(thermal_gap 0.0762)
		)
		(pad "3" thru_hole circle
			(at 2.307844 -2.307844)
			(size 0.9144 0.9144)
			(drill 0.5588)
			(layers "*.Cu" "*.Mask")
			(remove_unused_layers no)
			(net "GND")
			(clearance 0.0762)
			(thermal_gap 0.0762)
		)
		(pad "4" thru_hole circle
			(at 0 -3.2639)
			(size 0.9144 0.9144)
			(drill 0.5588)
			(layers "*.Cu" "*.Mask")
			(remove_unused_layers no)
			(net "GND")
			(clearance 0.0762)
			(thermal_gap 0.0762)
		)
		(pad "5" thru_hole circle
			(at -2.307844 -2.307844)
			(size 0.9144 0.9144)
			(drill 0.5588)
			(layers "*.Cu" "*.Mask")
			(remove_unused_layers no)
			(net "GND")
			(clearance 0.0762)
			(thermal_gap 0.0762)
		)
		(pad "6" thru_hole circle
			(at -3.2639 0)
			(size 0.9144 0.9144)
			(drill 0.5588)
			(layers "*.Cu" "*.Mask")
			(remove_unused_layers no)
			(net "GND")
			(clearance 0.0762)
			(thermal_gap 0.0762)
		)
		(pad "7" thru_hole circle
			(at -2.307844 2.307844)
			(size 0.9144 0.9144)
			(drill 0.5588)
			(layers "*.Cu" "*.Mask")
			(remove_unused_layers no)
			(net "GND")
			(clearance 0.0762)
			(thermal_gap 0.0762)
		)
		(pad "8" thru_hole circle
			(at 0 3.2639)
			(size 0.9144 0.9144)
			(drill 0.5588)
			(layers "*.Cu" "*.Mask")
			(remove_unused_layers no)
			(net "GND")
			(clearance 0.0762)
			(thermal_gap 0.0762)
		)
		(pad "9" thru_hole circle
			(at 2.307844 2.307844)
			(size 0.9144 0.9144)
			(drill 0.5588)
			(layers "*.Cu" "*.Mask")
			(remove_unused_layers no)
			(net "GND")
			(clearance 0.0762)
			(thermal_gap 0.0762)
		)
		(zone
			(layer "F.Cu")
			(hatch none 0.5)
			(connect_pads
				(clearance 0)
			)
			(min_thickness 0.25)
			(keepout
				(tracks not_allowed)
				(vias allowed)
				(pads allowed)
				(copperpour not_allowed)
				(footprints allowed)
			)
			(placement
				(enabled no)
				(sheetname "")
			)
			(fill
				(thermal_gap 0.5)
				(thermal_bridge_width 0.5)
				(island_removal_mode 0)
			)
			(polygon
				(pts
					(arc
						(start 258.12496 -356.49662)
						(mid 253.85776 -360.76382)
						(end 258.12496 -365.03102)
					)
					(arc
						(start 258.12496 -368.763804)
						(mid 252.468117 -366.420663)
						(end 250.124976 -360.76382)
					)
					(arc
						(start 250.124976 -360.76382)
						(mid 252.468117 -355.106977)
						(end 258.12496 -352.763836)
					)
				)
			)
		)
		(zone
			(layer "F.Cu")
			(hatch none 0.5)
			(connect_pads
				(clearance 0)
			)
			(min_thickness 0.25)
			(keepout
				(tracks not_allowed)
				(vias allowed)
				(pads allowed)
				(copperpour not_allowed)
				(footprints allowed)
			)
			(placement
				(enabled no)
				(sheetname "")
			)
			(fill
				(thermal_gap 0.5)
				(thermal_bridge_width 0.5)
				(island_removal_mode 0)
			)
			(polygon
				(pts
					(arc
						(start 258.12496 -356.49662)
						(mid 262.39216 -360.76382)
						(end 258.12496 -365.03102)
					)
					(arc
						(start 258.12496 -368.763804)
						(mid 263.781803 -366.420663)
						(end 266.124944 -360.76382)
					)
					(arc
						(start 266.124944 -360.76382)
						(mid 263.781803 -355.106977)
						(end 258.12496 -352.763836)
					)
				)
			)
		)
		(zone
			(layers "F.Cu" "B.Cu" "In1.Cu" "In2.Cu" "In3.Cu" "In4.Cu" "In5.Cu" "In6.Cu"
				"In7.Cu" "In8.Cu" "In9.Cu" "In10.Cu" "In11.Cu" "In12.Cu" "In13.Cu" "In14.Cu"
				"In15.Cu" "In16.Cu"
			)
			(hatch none 0.5)
			(connect_pads
				(clearance 0)
			)
			(min_thickness 0.25)
			(keepout
				(tracks not_allowed)
				(vias allowed)
				(pads allowed)
				(copperpour not_allowed)
				(footprints allowed)
			)
			(placement
				(enabled no)
				(sheetname "")
			)
			(fill
				(thermal_gap 0.5)
				(thermal_bridge_width 0.5)
				(island_removal_mode 0)
			)
			(polygon
				(pts
					(arc
						(start 260.63702 -360.76382)
						(mid 255.6129 -360.76382)
						(end 260.63702 -360.76382)
					)
				)
			)
		)
		(zone
			(layer "B.Cu")
			(hatch none 0.5)
			(connect_pads
				(clearance 0)
			)
			(min_thickness 0.25)
			(keepout
				(tracks not_allowed)
				(vias allowed)
				(pads allowed)
				(copperpour not_allowed)
				(footprints allowed)
			)
			(placement
				(enabled no)
				(sheetname "")
			)
			(fill
				(thermal_gap 0.5)
				(thermal_bridge_width 0.5)
				(island_removal_mode 0)
			)
			(polygon
				(pts
					(arc
						(start 258.12496 -365.28502)
						(mid 253.60376 -360.76382)
						(end 258.12496 -356.24262)
					)
					(arc
						(start 258.12496 -356.72522)
						(mid 254.08636 -360.76382)
						(end 258.12496 -364.80242)
					)
				)
			)
		)
		(zone
			(layer "B.Cu")
			(hatch none 0.5)
			(connect_pads
				(clearance 0)
			)
			(min_thickness 0.25)
			(keepout
				(tracks not_allowed)
				(vias allowed)
				(pads allowed)
				(copperpour not_allowed)
				(footprints allowed)
			)
			(placement
				(enabled no)
				(sheetname "")
			)
			(fill
				(thermal_gap 0.5)
				(thermal_bridge_width 0.5)
				(island_removal_mode 0)
			)
			(polygon
				(pts
					(arc
						(start 258.12496 -365.28502)
						(mid 262.64616 -360.76382)
						(end 258.12496 -356.24262)
					)
					(arc
						(start 258.12496 -356.72522)
						(mid 262.16356 -360.76382)
						(end 258.12496 -364.80242)
					)
				)
			)
		)
	)
)
